(kicad_pcb
	(version 20241229)
	(generator "pcbnew")
	(generator_version "9.0")
	(general
		(thickness 1.62)
		(legacy_teardrops no)
	)
	(paper "A3")
	(title_block
		(title "COM Express 7 Baseboard")
		(date "2025-02-04")
		(rev "1.1.2")
		(company "Antmicro Ltd")
		(comment 1 "www.antmicro.com")
		(comment 9 "footprints 49-53 of 802")
	)
	(layers
		(0 "F.Cu" signal)
		(4 "In1.Cu" signal)
		(6 "In2.Cu" signal)
		(8 "In3.Cu" signal)
		(10 "In4.Cu" signal)
		(12 "In5.Cu" signal)
		(14 "In6.Cu" signal)
		(2 "B.Cu" signal)
		(9 "F.Adhes" user "F.Adhesive")
		(11 "B.Adhes" user "B.Adhesive")
		(13 "F.Paste" user)
		(15 "B.Paste" user)
		(5 "F.SilkS" user "F.Silkscreen")
		(7 "B.SilkS" user "B.Silkscreen")
		(1 "F.Mask" user)
		(3 "B.Mask" user)
		(17 "Dwgs.User" user "User.Drawings")
		(19 "Cmts.User" user "User.Comments")
		(21 "Eco1.User" user "User.Eco1")
		(23 "Eco2.User" user "User.Eco2")
		(25 "Edge.Cuts" user)
		(27 "Margin" user)
		(31 "F.CrtYd" user "F.Courtyard")
		(29 "B.CrtYd" user "B.Courtyard")
		(35 "F.Fab" user)
		(33 "B.Fab" user)
	)
	(footprint "antmicro-footprints:R_0402_1005Metric"
		(layer "F.Cu")
		(at 163.1 160.36)
		(descr "Resistor SMD 0402")
		(tags "resistor SMD 0402")
		(property "Reference" "R31"
			(at 0.8 0.48 0)
			(layer "F.SilkS")
			(effects
				(font
					(size 0.7 0.7)
					(thickness 0.15)
				)
				(justify left bottom)
			)
		)
		(property "Value" "R_0R_0402"
			(at -1.011843 1.772047 0)
			(layer "F.Fab")
			(effects
				(font
					(size 0.7 0.7)
					(thickness 0.15)
				)
				(justify left bottom)
			)
		)
		(property "Datasheet" "https://industrial.panasonic.com/cdbs/www-data/pdf/RDA0000/AOA0000C301.pdf"
			(at 0 0 0)
			(layer "F.Fab")
			(hide yes)
			(effects
				(font
					(size 1.27 1.27)
					(thickness 0.15)
				)
			)
		)
		(property "Author" "Antmicro"
			(at 0 0 0)
			(layer "F.Fab")
			(hide yes)
			(effects
				(font
					(size 1 1)
					(thickness 0.15)
				)
			)
		)
		(property "Current" "1A"
			(at 0 0 0)
			(layer "F.Fab")
			(hide yes)
			(effects
				(font
					(size 1 1)
					(thickness 0.15)
				)
			)
		)
		(property "License" "Apache-2.0"
			(at 0 0 0)
			(layer "F.Fab")
			(hide yes)
			(effects
				(font
					(size 1 1)
					(thickness 0.15)
				)
			)
		)
		(property "MPN" "ERJ2GE0R00X"
			(at 0 0 0)
			(layer "F.Fab")
			(hide yes)
			(effects
				(font
					(size 1 1)
					(thickness 0.15)
				)
			)
		)
		(property "Manufacturer" "Panasonic"
			(at 0 0 0)
			(layer "F.Fab")
			(hide yes)
			(effects
				(font
					(size 1 1)
					(thickness 0.15)
				)
			)
		)
		(property "Public" "False"
			(at 0 0 0)
			(layer "F.Fab")
			(hide yes)
			(effects
				(font
					(size 1 1)
					(thickness 0.15)
				)
			)
		)
		(property "Tolerance" ""
			(at 0 0 0)
			(layer "F.Fab")
			(hide yes)
			(effects
				(font
					(size 1 1)
					(thickness 0.15)
				)
			)
		)
		(property "Val" "0R"
			(at 0 0 0)
			(layer "F.Fab")
			(hide yes)
			(effects
				(font
					(size 1 1)
					(thickness 0.15)
				)
			)
		)
		(sheetname "2xSFP+")
		(sheetfile "2xSFP+.kicad_sch")
		(attr smd)
		(fp_rect
			(start -0.925 -0.47)
			(end 0.925 0.47)
			(stroke
				(width 0.05)
				(type default)
			)
			(fill no)
			(layer "F.CrtYd")
		)
		(fp_rect
			(start -0.5 -0.25)
			(end 0.5 0.25)
			(stroke
				(width 0.15)
				(type solid)
			)
			(fill no)
			(layer "F.Fab")
		)
		(pad "1" smd roundrect
			(at -0.48 0)
			(size 0.59 0.64)
			(layers "F.Cu" "F.Mask" "F.Paste")
			(roundrect_rratio 0.25)
			(net 557 "Net-(U5-A0)")
			(pintype "passive")
			(teardrops
				(best_length_ratio 0.2)
				(max_length 1)
				(best_width_ratio 0.9)
				(max_width 2)
				(curved_edges yes)
				(filter_ratio 0.9)
				(enabled yes)
				(allow_two_segments yes)
				(prefer_zone_connections yes)
			)
		)
		(pad "2" smd roundrect
			(at 0.48 0)
			(size 0.59 0.64)
			(layers "F.Cu" "F.Mask" "F.Paste")
			(roundrect_rratio 0.25)
			(net 2 "+3V3")
			(pintype "passive")
			(teardrops
				(best_length_ratio 0.2)
				(max_length 1)
				(best_width_ratio 0.9)
				(max_width 2)
				(curved_edges yes)
				(filter_ratio 0.9)
				(enabled yes)
				(allow_two_segments yes)
				(prefer_zone_connections yes)
			)
		)
	)
	(footprint "antmicro-footprints:R_0402_1005Metric"
		(layer "F.Cu")
		(at 214.98 135 -90)
		(descr "Resistor SMD 0402")
		(tags "resistor SMD 0402")
		(property "Reference" "R197"
			(at 0.81 -0.42 90)
			(layer "F.SilkS")
			(effects
				(font
					(size 0.7 0.7)
					(thickness 0.15)
				)
				(justify right bottom)
			)
		)
		(property "Value" "R_0R_0402"
			(at -1.011843 1.772047 90)
			(layer "F.Fab")
			(effects
				(font
					(size 0.7 0.7)
					(thickness 0.15)
				)
				(justify right bottom)
			)
		)
		(property "Datasheet" "https://industrial.panasonic.com/cdbs/www-data/pdf/RDA0000/AOA0000C301.pdf"
			(at 0 0 270)
			(layer "F.Fab")
			(hide yes)
			(effects
				(font
					(size 1.27 1.27)
					(thickness 0.15)
				)
			)
		)
		(property "Author" "Antmicro"
			(at 79.98 349.98 0)
			(layer "F.Fab")
			(hide yes)
			(effects
				(font
					(size 1 1)
					(thickness 0.15)
				)
			)
		)
		(property "Current" "1A"
			(at 79.98 349.98 0)
			(layer "F.Fab")
			(hide yes)
			(effects
				(font
					(size 1 1)
					(thickness 0.15)
				)
			)
		)
		(property "License" "Apache-2.0"
			(at 79.98 349.98 0)
			(layer "F.Fab")
			(hide yes)
			(effects
				(font
					(size 1 1)
					(thickness 0.15)
				)
			)
		)
		(property "MPN" "ERJ2GE0R00X"
			(at 79.98 349.98 0)
			(layer "F.Fab")
			(hide yes)
			(effects
				(font
					(size 1 1)
					(thickness 0.15)
				)
			)
		)
		(property "Manufacturer" "Panasonic"
			(at 79.98 349.98 0)
			(layer "F.Fab")
			(hide yes)
			(effects
				(font
					(size 1 1)
					(thickness 0.15)
				)
			)
		)
		(property "Public" "False"
			(at 79.98 349.98 0)
			(layer "F.Fab")
			(hide yes)
			(effects
				(font
					(size 1 1)
					(thickness 0.15)
				)
			)
		)
		(property "Tolerance" ""
			(at 79.98 349.98 0)
			(layer "F.Fab")
			(hide yes)
			(effects
				(font
					(size 1 1)
					(thickness 0.15)
				)
			)
		)
		(property "Val" "0R"
			(at 79.98 349.98 0)
			(layer "F.Fab")
			(hide yes)
			(effects
				(font
					(size 1 1)
					(thickness 0.15)
				)
			)
		)
		(sheetname "PCIe misc")
		(sheetfile "pcie_misc.kicad_sch")
		(attr smd)
		(fp_rect
			(start -0.925 -0.47)
			(end 0.925 0.47)
			(stroke
				(width 0.05)
				(type default)
			)
			(fill no)
			(layer "F.CrtYd")
		)
		(fp_rect
			(start -0.5 -0.25)
			(end 0.5 0.25)
			(stroke
				(width 0.15)
				(type solid)
			)
			(fill no)
			(layer "F.Fab")
		)
		(pad "1" smd roundrect
			(at -0.48 0 270)
			(size 0.59 0.64)
			(layers "F.Cu" "F.Mask" "F.Paste")
			(roundrect_rratio 0.25)
			(net 616 "/PCIe misc/DIF2-")
			(pintype "passive")
			(teardrops
				(best_length_ratio 0.2)
				(max_length 1)
				(best_width_ratio 0.9)
				(max_width 2)
				(curved_edges yes)
				(filter_ratio 0.9)
				(enabled yes)
				(allow_two_segments yes)
				(prefer_zone_connections yes)
			)
		)
		(pad "2" smd roundrect
			(at 0.48 0 270)
			(size 0.59 0.64)
			(layers "F.Cu" "F.Mask" "F.Paste")
			(roundrect_rratio 0.25)
			(net 19 "/M.2 key E/PCIE_{REF}.CK+")
			(pintype "passive")
			(teardrops
				(best_length_ratio 0.2)
				(max_length 1)
				(best_width_ratio 0.9)
				(max_width 2)
				(curved_edges yes)
				(filter_ratio 0.9)
				(enabled yes)
				(allow_two_segments yes)
				(prefer_zone_connections yes)
			)
		)
	)
	(footprint "antmicro-footprints:R_0402_1005Metric"
		(layer "F.Cu")
		(at 216.98 133.12 -90)
		(descr "Resistor SMD 0402")
		(tags "resistor SMD 0402")
		(property "Reference" "R199"
			(at 2.44 -5.32 90)
			(layer "F.SilkS")
			(effects
				(font
					(size 0.7 0.7)
					(thickness 0.15)
				)
				(justify right bottom)
			)
		)
		(property "Value" "R_0R_0402"
			(at -1.011843 1.772047 90)
			(layer "F.Fab")
			(effects
				(font
					(size 0.7 0.7)
					(thickness 0.15)
				)
				(justify right bottom)
			)
		)
		(property "Datasheet" "https://industrial.panasonic.com/cdbs/www-data/pdf/RDA0000/AOA0000C301.pdf"
			(at 0 0 270)
			(layer "F.Fab")
			(hide yes)
			(effects
				(font
					(size 1.27 1.27)
					(thickness 0.15)
				)
			)
		)
		(property "Author" "Antmicro"
			(at 83.86 350.1 0)
			(layer "F.Fab")
			(hide yes)
			(effects
				(font
					(size 1 1)
					(thickness 0.15)
				)
			)
		)
		(property "Current" "1A"
			(at 83.86 350.1 0)
			(layer "F.Fab")
			(hide yes)
			(effects
				(font
					(size 1 1)
					(thickness 0.15)
				)
			)
		)
		(property "License" "Apache-2.0"
			(at 83.86 350.1 0)
			(layer "F.Fab")
			(hide yes)
			(effects
				(font
					(size 1 1)
					(thickness 0.15)
				)
			)
		)
		(property "MPN" "ERJ2GE0R00X"
			(at 83.86 350.1 0)
			(layer "F.Fab")
			(hide yes)
			(effects
				(font
					(size 1 1)
					(thickness 0.15)
				)
			)
		)
		(property "Manufacturer" "Panasonic"
			(at 83.86 350.1 0)
			(layer "F.Fab")
			(hide yes)
			(effects
				(font
					(size 1 1)
					(thickness 0.15)
				)
			)
		)
		(property "Public" "False"
			(at 83.86 350.1 0)
			(layer "F.Fab")
			(hide yes)
			(effects
				(font
					(size 1 1)
					(thickness 0.15)
				)
			)
		)
		(property "Tolerance" ""
			(at 83.86 350.1 0)
			(layer "F.Fab")
			(hide yes)
			(effects
				(font
					(size 1 1)
					(thickness 0.15)
				)
			)
		)
		(property "Val" "0R"
			(at 83.86 350.1 0)
			(layer "F.Fab")
			(hide yes)
			(effects
				(font
					(size 1 1)
					(thickness 0.15)
				)
			)
		)
		(sheetname "PCIe misc")
		(sheetfile "pcie_misc.kicad_sch")
		(attr smd)
		(fp_rect
			(start -0.925 -0.47)
			(end 0.925 0.47)
			(stroke
				(width 0.05)
				(type default)
			)
			(fill no)
			(layer "F.CrtYd")
		)
		(fp_rect
			(start -0.5 -0.25)
			(end 0.5 0.25)
			(stroke
				(width 0.15)
				(type solid)
			)
			(fill no)
			(layer "F.Fab")
		)
		(pad "1" smd roundrect
			(at -0.48 0 270)
			(size 0.59 0.64)
			(layers "F.Cu" "F.Mask" "F.Paste")
			(roundrect_rratio 0.25)
			(net 618 "/PCIe misc/DIF3-")
			(pintype "passive")
			(teardrops
				(best_length_ratio 0.2)
				(max_length 1)
				(best_width_ratio 0.9)
				(max_width 2)
				(curved_edges yes)
				(filter_ratio 0.9)
				(enabled yes)
				(allow_two_segments yes)
				(prefer_zone_connections yes)
			)
		)
		(pad "2" smd roundrect
			(at 0.48 0 270)
			(size 0.59 0.64)
			(layers "F.Cu" "F.Mask" "F.Paste")
			(roundrect_rratio 0.25)
			(net 205 "/Backplane/PCIe_{REF}.CK-")
			(pintype "passive")
			(teardrops
				(best_length_ratio 0.2)
				(max_length 1)
				(best_width_ratio 0.9)
				(max_width 2)
				(curved_edges yes)
				(filter_ratio 0.9)
				(enabled yes)
				(allow_two_segments yes)
				(prefer_zone_connections yes)
			)
		)
	)
	(footprint "antmicro-footprints:R_0402_1005Metric"
		(layer "F.Cu")
		(at 287.95 101.86 180)
		(descr "Resistor SMD 0402")
		(tags "resistor SMD 0402")
		(property "Reference" "R116"
			(at 0.8 -0.4 0)
			(layer "F.SilkS")
			(effects
				(font
					(size 0.7 0.7)
					(thickness 0.15)
				)
				(justify right bottom)
			)
		)
		(property "Value" "R_10k_0402"
			(at -1.011843 1.772047 0)
			(layer "F.Fab")
			(effects
				(font
					(size 0.7 0.7)
					(thickness 0.15)
				)
				(justify right bottom)
			)
		)
		(property "Datasheet" "https://www.bourns.com/docs/product-datasheets/cr.pdf"
			(at 0 0 180)
			(layer "F.Fab")
			(hide yes)
			(effects
				(font
					(size 1.27 1.27)
					(thickness 0.15)
				)
			)
		)
		(property "Author" "Antmicro"
			(at 575.9 203.72 0)
			(layer "F.Fab")
			(hide yes)
			(effects
				(font
					(size 1 1)
					(thickness 0.15)
				)
			)
		)
		(property "License" "Apache-2.0"
			(at 575.9 203.72 0)
			(layer "F.Fab")
			(hide yes)
			(effects
				(font
					(size 1 1)
					(thickness 0.15)
				)
			)
		)
		(property "MPN" "CR0402-FX-1002GLF"
			(at 575.9 203.72 0)
			(layer "F.Fab")
			(hide yes)
			(effects
				(font
					(size 1 1)
					(thickness 0.15)
				)
			)
		)
		(property "Manufacturer" "Bourns"
			(at 575.9 203.72 0)
			(layer "F.Fab")
			(hide yes)
			(effects
				(font
					(size 1 1)
					(thickness 0.15)
				)
			)
		)
		(property "Public" "False"
			(at 575.9 203.72 0)
			(layer "F.Fab")
			(hide yes)
			(effects
				(font
					(size 1 1)
					(thickness 0.15)
				)
			)
		)
		(property "Tolerance" "1%"
			(at 575.9 203.72 0)
			(layer "F.Fab")
			(hide yes)
			(effects
				(font
					(size 1 1)
					(thickness 0.15)
				)
			)
		)
		(property "Val" "10k"
			(at 575.9 203.72 0)
			(layer "F.Fab")
			(hide yes)
			(effects
				(font
					(size 1 1)
					(thickness 0.15)
				)
			)
		)
		(sheetname "Power")
		(sheetfile "power.kicad_sch")
		(attr smd)
		(fp_rect
			(start -0.925 -0.47)
			(end 0.925 0.47)
			(stroke
				(width 0.05)
				(type default)
			)
			(fill no)
			(layer "F.CrtYd")
		)
		(fp_rect
			(start -0.5 -0.25)
			(end 0.5 0.25)
			(stroke
				(width 0.15)
				(type solid)
			)
			(fill no)
			(layer "F.Fab")
		)
		(pad "1" smd roundrect
			(at -0.48 0 180)
			(size 0.59 0.64)
			(layers "F.Cu" "F.Mask" "F.Paste")
			(roundrect_rratio 0.25)
			(net 535 "Net-(Q3-G)")
			(pintype "passive")
			(teardrops
				(best_length_ratio 0.2)
				(max_length 1)
				(best_width_ratio 0.9)
				(max_width 2)
				(curved_edges yes)
				(filter_ratio 0.9)
				(enabled yes)
				(allow_two_segments yes)
				(prefer_zone_connections yes)
			)
		)
		(pad "2" smd roundrect
			(at 0.48 0 180)
			(size 0.59 0.64)
			(layers "F.Cu" "F.Mask" "F.Paste")
			(roundrect_rratio 0.25)
			(net 65 "+12V")
			(pintype "passive")
			(teardrops
				(best_length_ratio 0.2)
				(max_length 1)
				(best_width_ratio 0.9)
				(max_width 2)
				(curved_edges yes)
				(filter_ratio 0.9)
				(enabled yes)
				(allow_two_segments yes)
				(prefer_zone_connections yes)
			)
		)
	)
	(footprint "antmicro-footprints:C_0402_1005Metric"
		(layer "F.Cu")
		(at 159.55 156.81 -90)
		(descr "Capacitor SMD 0402")
		(tags "capacitor SMD 0402")
		(property "Reference" "C21"
			(at -3.013 -0.449 90)
			(layer "F.SilkS")
			(effects
				(font
					(size 0.7 0.7)
					(thickness 0.15)
				)
				(justify right bottom)
			)
		)
		(property "Value" "C_100n_0402"
			(at -1.022927 2.155213 90)
			(layer "F.Fab")
			(effects
				(font
					(size 0.7 0.7)
					(thickness 0.15)
				)
				(justify right bottom)
			)
		)
		(property "Datasheet" "https://www.murata.com/products/productdetail?partno=GRM155R61H104KE14%23"
			(at 0 0 270)
			(layer "F.Fab")
			(hide yes)
			(effects
				(font
					(size 1.27 1.27)
					(thickness 0.15)
				)
			)
		)
		(property "Author" "Antmicro"
			(at 2.74 316.36 0)
			(layer "F.Fab")
			(hide yes)
			(effects
				(font
					(size 1 1)
					(thickness 0.15)
				)
			)
		)
		(property "Dielectric" "X5R"
			(at 2.74 316.36 0)
			(layer "F.Fab")
			(hide yes)
			(effects
				(font
					(size 1 1)
					(thickness 0.15)
				)
			)
		)
		(property "License" "Apache-2.0"
			(at 2.74 316.36 0)
			(layer "F.Fab")
			(hide yes)
			(effects
				(font
					(size 1 1)
					(thickness 0.15)
				)
			)
		)
		(property "MPN" "GRM155R61H104KE14D"
			(at 2.74 316.36 0)
			(layer "F.Fab")
			(hide yes)
			(effects
				(font
					(size 1 1)
					(thickness 0.15)
				)
			)
		)
		(property "Manufacturer" "Murata"
			(at 2.74 316.36 0)
			(layer "F.Fab")
			(hide yes)
			(effects
				(font
					(size 1 1)
					(thickness 0.15)
				)
			)
		)
		(property "Public" "False"
			(at 2.74 316.36 0)
			(layer "F.Fab")
			(hide yes)
			(effects
				(font
					(size 1 1)
					(thickness 0.15)
				)
			)
		)
		(property "Val" "100n"
			(at 2.74 316.36 0)
			(layer "F.Fab")
			(hide yes)
			(effects
				(font
					(size 1 1)
					(thickness 0.15)
				)
			)
		)
		(property "Voltage" "50V"
			(at 2.74 316.36 0)
			(layer "F.Fab")
			(hide yes)
			(effects
				(font
					(size 1 1)
					(thickness 0.15)
				)
			)
		)
		(sheetname "2xSFP+")
		(sheetfile "2xSFP+.kicad_sch")
		(attr smd)
		(fp_rect
			(start -0.925 -0.47)
			(end 0.925 0.47)
			(stroke
				(width 0.05)
				(type default)
			)
			(fill no)
			(layer "F.CrtYd")
		)
		(fp_line
			(start -0.494 0.248)
			(end -0.494 -0.25)
			(stroke
				(width 0.15)
				(type solid)
			)
			(layer "F.Fab")
		)
		(fp_line
			(start 0.504 0.248)
			(end -0.494 0.248)
			(stroke
				(width 0.15)
				(type solid)
			)
			(layer "F.Fab")
		)
		(fp_line
			(start -0.494 -0.25)
			(end 0.504 -0.25)
			(stroke
				(width 0.15)
				(type solid)
			)
			(layer "F.Fab")
		)
		(fp_line
			(start 0.504 -0.25)
			(end 0.504 0.248)
			(stroke
				(width 0.15)
				(type solid)
			)
			(layer "F.Fab")
		)
		(pad "1" smd roundrect
			(at -0.48 0 270)
			(size 0.59 0.64)
			(layers "F.Cu" "F.Mask" "F.Paste")
			(roundrect_rratio 0.25)
			(net 1 "GND")
			(pintype "passive")
			(teardrops
				(best_length_ratio 0.2)
				(max_length 1)
				(best_width_ratio 0.9)
				(max_width 2)
				(curved_edges yes)
				(filter_ratio 0.9)
				(enabled yes)
				(allow_two_segments yes)
				(prefer_zone_connections yes)
			)
		)
		(pad "2" smd roundrect
			(at 0.48 0 270)
			(size 0.59 0.64)
			(layers "F.Cu" "F.Mask" "F.Paste")
			(roundrect_rratio 0.25)
			(net 2 "+3V3")
			(pintype "passive")
			(teardrops
				(best_length_ratio 0.2)
				(max_length 1)
				(best_width_ratio 0.9)
				(max_width 2)
				(curved_edges yes)
				(filter_ratio 0.9)
				(enabled yes)
				(allow_two_segments yes)
				(prefer_zone_connections yes)
			)
		)
	)
)
